#ISCELL
  pure_quanta quanta_title_block_c *
  *
#CELL
  pure_quanta pt5161lrs *
  page437_i1
#ISCELL
  standard tap *
  page437_i10
#ISCELL
  standard tap *
  page437_i11
#ISCELL
  standard tap *
  page437_i12
#ISCELL
  standard tap *
  page437_i13
#ISCELL
  standard tap *
  page437_i14
#ISCELL
  standard tap *
  page437_i15
#ISCELL
  standard tap *
  page437_i16
#ISCELL
  standard tap *
  page437_i17
#ISCELL
  standard offpage *
  page437_i18
#ISCELL
  standard offpage *
  page437_i19
#ISCELL
  standard tap *
  page437_i2
#ISCELL
  standard tap *
  page437_i20
#ISCELL
  standard tap *
  page437_i21
#ISCELL
  standard tap *
  page437_i22
#ISCELL
  standard tap *
  page437_i23
#ISCELL
  standard tap *
  page437_i24
#ISCELL
  standard tap *
  page437_i25
#ISCELL
  standard tap *
  page437_i26
#ISCELL
  standard tap *
  page437_i27
#ISCELL
  standard tap *
  page437_i28
#ISCELL
  standard tap *
  page437_i29
#ISCELL
  standard tap *
  page437_i3
#ISCELL
  standard tap *
  page437_i30
#ISCELL
  standard tap *
  page437_i31
#ISCELL
  standard tap *
  page437_i32
#ISCELL
  standard tap *
  page437_i33
#ISCELL
  standard tap *
  page437_i34
#ISCELL
  standard tap *
  page437_i35
#ISCELL
  standard offpage *
  page437_i36
#ISCELL
  standard offpage *
  page437_i37
#CELL
  pure_quanta pt5161lrs *
  page437_i38
#ISCELL
  standard tap *
  page437_i4
#ISCELL
  standard tap *
  page437_i5
#ISCELL
  standard tap *
  page437_i6
#ISCELL
  standard tap *
  page437_i7
#ISCELL
  standard tap *
  page437_i8
#ISCELL
  standard tap *
  page437_i9
